# T6G (Grand Teton) — schematic netlist excerpt (pin names and nets, part order shuffled) for the footprints in the layout excerpt that follows; sources: Cadence DE-HDL packaged netlist, KiCad conversion of 04192023_DAF0TMB3IC0_F0TG_MB_C_brd_V02_OCP.brd

R1103  Q_RES  10K 1% CHIP  pkg 0201LF  page 309 : A = RST_RT_CPU0_P3_PERST_R_N ; B = GND
C2048  Q_CAP  0.1UF 25V 10% X7R  pkg 0402  page 257 : A = P3V3_ADC_TIC ; B = GND
R1671  Q_RES  0 5% CHIP  pkg 0402LF  page 131 : A = OCP_SFF_AUX_PWR_EN ; B = OCP_SFF_AUX_PWR_EN_R

(kicad_pcb
	(version 20260206)
	(generator "pcbnew")
	(generator_version "10.0")
	(general
		(thickness 1.6)
		(legacy_teardrops no)
	)
	(paper "A4")
	(title_block
		(title "04192023_DAF0TMB3IC0_F0TG_MB_C_brd_V02_OCP.brd")
		(comment 1 "Grand Teton / footprints 3622-3624 of 8354")
	)
	(layers
		(0 "F.Cu" signal "TOP")
		(4 "In1.Cu" signal "GND")
		(6 "In2.Cu" signal "IN1")
		(8 "In3.Cu" signal "GND1")
		(10 "In4.Cu" signal "IN2")
		(12 "In5.Cu" signal "GND2")
		(14 "In6.Cu" signal "IN3")
		(16 "In7.Cu" signal "GND3")
		(18 "In8.Cu" signal "VCC")
		(20 "In9.Cu" signal "VCC1")
		(22 "In10.Cu" signal "GND4")
		(24 "In11.Cu" signal "IN4")
		(26 "In12.Cu" signal "GND5")
		(28 "In13.Cu" signal "IN5")
		(30 "In14.Cu" signal "GND6")
		(32 "In15.Cu" signal "IN6")
		(34 "In16.Cu" signal "GND7")
		(2 "B.Cu" signal "BOTTOM")
		(9 "F.Adhes" user "F.Adhesive")
		(11 "B.Adhes" user "B.Adhesive")
		(13 "F.Paste" user "Package Geometry/Pastemask Top")
		(15 "B.Paste" user "Package Geometry/Pastemask Bottom")
		(5 "F.SilkS" user "Ref Des/Silkscreen Top")
		(7 "B.SilkS" user "Ref Des/Silkscreen Bottom")
		(1 "F.Mask" user "Board Geometry/Soldermask Top")
		(3 "B.Mask" user "Board Geometry/Soldermask Bottom")
		(17 "Dwgs.User" user "User.Drawings")
		(19 "Cmts.User" user "User.Comments")
		(21 "Eco1.User" user "User.Eco1")
		(23 "Eco2.User" user "User.Eco2")
		(25 "Edge.Cuts" user "Board Geometry/Outline")
		(27 "Margin" user)
		(31 "F.CrtYd" user "Package Geometry/Place Bound Top")
		(29 "B.CrtYd" user "Package Geometry/Place Bound Bottom")
		(35 "F.Fab" user "Ref Des/Assembly Top")
		(33 "B.Fab" user "Ref Des/Assembly Bottom")
	)
	(footprint ""
		(layer "F.Cu")
		(at 319.940178 -42.684954)
		(property "Reference" "C2048"
			(at 0 0 0)
			(layer "F.SilkS")
			(hide yes)
			(effects
				(font
					(size 1.27 1.27)
				)
			)
		)
		(property "Value" ""
			(at 0 0 0)
			(layer "F.Fab")
			(effects
				(font
					(size 1.27 1.27)
				)
			)
		)
		(duplicate_pad_numbers_are_jumpers no)
		(fp_line
			(start -0.7874 -0.4064)
			(end 0.7874 -0.4064)
			(stroke
				(width 0.1524)
				(type default)
			)
			(layer "F.SilkS")
		)
		(fp_line
			(start -0.7874 0.4064)
			(end -0.7874 -0.4064)
			(stroke
				(width 0.1524)
				(type default)
			)
			(layer "F.SilkS")
		)
		(fp_line
			(start 0.7874 -0.4064)
			(end 0.7874 0.4064)
			(stroke
				(width 0.1524)
				(type default)
			)
			(layer "F.SilkS")
		)
		(fp_line
			(start 0.7874 0.4064)
			(end -0.7874 0.4064)
			(stroke
				(width 0.1524)
				(type default)
			)
			(layer "F.SilkS")
		)
		(fp_line
			(start -0.67945 -0.305054)
			(end -0.12065 -0.305054)
			(stroke
				(width 0.1)
				(type default)
			)
			(layer "F.Fab")
		)
		(fp_line
			(start -0.67945 0.3048)
			(end -0.67945 -0.305054)
			(stroke
				(width 0.1)
				(type default)
			)
			(layer "F.Fab")
		)
		(fp_line
			(start -0.12065 -0.305054)
			(end -0.12065 -0.2794)
			(stroke
				(width 0.1)
				(type default)
			)
			(layer "F.Fab")
		)
		(fp_line
			(start -0.12065 -0.2794)
			(end 0.12065 -0.2794)
			(stroke
				(width 0.1)
				(type default)
			)
			(layer "F.Fab")
		)
		(fp_line
			(start -0.12065 0.2794)
			(end -0.12065 0.3048)
			(stroke
				(width 0.1)
				(type default)
			)
			(layer "F.Fab")
		)
		(fp_line
			(start -0.12065 0.3048)
			(end -0.67945 0.3048)
			(stroke
				(width 0.1)
				(type default)
			)
			(layer "F.Fab")
		)
		(fp_line
			(start 0.120396 0.2794)
			(end -0.12065 0.2794)
			(stroke
				(width 0.1)
				(type default)
			)
			(layer "F.Fab")
		)
		(fp_line
			(start 0.120396 0.3048)
			(end 0.120396 0.2794)
			(stroke
				(width 0.1)
				(type default)
			)
			(layer "F.Fab")
		)
		(fp_line
			(start 0.12065 -0.3048)
			(end 0.67945 -0.3048)
			(stroke
				(width 0.1)
				(type default)
			)
			(layer "F.Fab")
		)
		(fp_line
			(start 0.12065 -0.2794)
			(end 0.12065 -0.3048)
			(stroke
				(width 0.1)
				(type default)
			)
			(layer "F.Fab")
		)
		(fp_line
			(start 0.67945 -0.3048)
			(end 0.67945 0.3048)
			(stroke
				(width 0.1)
				(type default)
			)
			(layer "F.Fab")
		)
		(fp_line
			(start 0.67945 0.3048)
			(end 0.120396 0.3048)
			(stroke
				(width 0.1)
				(type default)
			)
			(layer "F.Fab")
		)
		(pad "1" smd circle
			(at -0.40005 0)
			(size 0 0)
			(layers "F.Cu" "F.Mask" "F.Paste")
			(net "P3V3_ADC_TIC")
		)
		(pad "2" smd circle
			(at 0.40005 0)
			(size 0 0)
			(layers "F.Cu" "F.Mask" "F.Paste")
			(net "GND")
		)
	)
	(footprint ""
		(layer "F.Cu")
		(at 434.796692 -16.199866 -90)
		(property "Reference" "R1671"
			(at 0 0 270)
			(layer "F.SilkS")
			(hide yes)
			(effects
				(font
					(size 1.27 1.27)
				)
			)
		)
		(property "Value" ""
			(at 0 0 270)
			(layer "F.Fab")
			(effects
				(font
					(size 1.27 1.27)
				)
			)
		)
		(duplicate_pad_numbers_are_jumpers no)
		(fp_line
			(start -0.7874 0.4064)
			(end -0.7874 -0.4064)
			(stroke
				(width 0.1524)
				(type default)
			)
			(layer "F.SilkS")
		)
		(fp_line
			(start 0.7874 0.4064)
			(end -0.7874 0.4064)
			(stroke
				(width 0.1524)
				(type default)
			)
			(layer "F.SilkS")
		)
		(fp_line
			(start -0.7874 -0.4064)
			(end 0.7874 -0.4064)
			(stroke
				(width 0.1524)
				(type default)
			)
			(layer "F.SilkS")
		)
		(fp_line
			(start 0.7874 -0.4064)
			(end 0.7874 0.4064)
			(stroke
				(width 0.1524)
				(type default)
			)
			(layer "F.SilkS")
		)
		(fp_line
			(start -0.67945 0.3048)
			(end -0.67945 -0.305054)
			(stroke
				(width 0.1)
				(type default)
			)
			(layer "F.Fab")
		)
		(fp_line
			(start -0.12065 0.3048)
			(end -0.67945 0.3048)
			(stroke
				(width 0.1)
				(type default)
			)
			(layer "F.Fab")
		)
		(fp_line
			(start 0.120396 0.3048)
			(end 0.120396 0.2794)
			(stroke
				(width 0.1)
				(type default)
			)
			(layer "F.Fab")
		)
		(fp_line
			(start 0.67945 0.3048)
			(end 0.120396 0.3048)
			(stroke
				(width 0.1)
				(type default)
			)
			(layer "F.Fab")
		)
		(fp_line
			(start -0.12065 0.2794)
			(end -0.12065 0.3048)
			(stroke
				(width 0.1)
				(type default)
			)
			(layer "F.Fab")
		)
		(fp_line
			(start 0.120396 0.2794)
			(end -0.12065 0.2794)
			(stroke
				(width 0.1)
				(type default)
			)
			(layer "F.Fab")
		)
		(fp_line
			(start -0.12065 -0.2794)
			(end 0.12065 -0.2794)
			(stroke
				(width 0.1)
				(type default)
			)
			(layer "F.Fab")
		)
		(fp_line
			(start 0.12065 -0.2794)
			(end 0.12065 -0.3048)
			(stroke
				(width 0.1)
				(type default)
			)
			(layer "F.Fab")
		)
		(fp_line
			(start 0.12065 -0.3048)
			(end 0.67945 -0.3048)
			(stroke
				(width 0.1)
				(type default)
			)
			(layer "F.Fab")
		)
		(fp_line
			(start 0.67945 -0.3048)
			(end 0.67945 0.3048)
			(stroke
				(width 0.1)
				(type default)
			)
			(layer "F.Fab")
		)
		(fp_line
			(start -0.67945 -0.305054)
			(end -0.12065 -0.305054)
			(stroke
				(width 0.1)
				(type default)
			)
			(layer "F.Fab")
		)
		(fp_line
			(start -0.12065 -0.305054)
			(end -0.12065 -0.2794)
			(stroke
				(width 0.1)
				(type default)
			)
			(layer "F.Fab")
		)
		(pad "1" smd circle
			(at -0.40005 0 270)
			(size 0 0)
			(layers "F.Cu" "F.Mask" "F.Paste")
			(net "OCP_SFF_AUX_PWR_EN")
		)
		(pad "2" smd circle
			(at 0.40005 0 270)
			(size 0 0)
			(layers "F.Cu" "F.Mask" "F.Paste")
			(net "OCP_SFF_AUX_PWR_EN_R")
		)
	)
	(footprint ""
		(layer "F.Cu")
		(at 391.268458 -402.7424 -90)
		(property "Reference" "R1103"
			(at 0 0 270)
			(layer "F.SilkS")
			(hide yes)
			(effects
				(font
					(size 1.27 1.27)
				)
			)
		)
		(property "Value" ""
			(at 0 0 270)
			(layer "F.Fab")
			(effects
				(font
					(size 1.27 1.27)
				)
			)
		)
		(duplicate_pad_numbers_are_jumpers no)
		(fp_line
			(start -0.32512 0.175006)
			(end -0.32512 -0.175006)
			(stroke
				(width 0.1)
				(type default)
			)
			(layer "F.Fab")
		)
		(fp_line
			(start 0.32512 0.175006)
			(end -0.32512 0.175006)
			(stroke
				(width 0.1)
				(type default)
			)
			(layer "F.Fab")
		)
		(fp_line
			(start -0.32512 -0.175006)
			(end 0.32512 -0.175006)
			(stroke
				(width 0.1)
				(type default)
			)
			(layer "F.Fab")
		)
		(fp_line
			(start 0.32512 -0.175006)
			(end 0.32512 0.175006)
			(stroke
				(width 0.1)
				(type default)
			)
			(layer "F.Fab")
		)
		(pad "1" smd rect
			(at -0.2667 0 270)
			(size 0.3048 0.381)
			(layers "F.Cu" "F.Mask" "F.Paste")
			(net "RST_RT_CPU0_P3_PERST_R_N")
		)
		(pad "2" smd rect
			(at 0.2667 0 90)
			(size 0.3048 0.381)
			(layers "F.Cu" "F.Mask" "F.Paste")
			(net "GND")
		)
	)
)
